(kicad_pcb
	(version 20260206)
	(generator "pcbnew")
	(generator_version "10.0")
	(general
		(thickness 1.6)
		(legacy_teardrops no)
	)
	(paper "A4")
	(title_block
		(title "Wiwynn_Tioga_Pass_MB.brd")
		(comment 1 "Tioga Pass / footprint 2988 of 4770 (J6U1), pads 1-123 of 291")
	)
	(layers
		(0 "F.Cu" signal "TOP")
		(4 "In1.Cu" signal "L2GND")
		(6 "In2.Cu" signal "L3")
		(8 "In3.Cu" signal "L4GND")
		(10 "In4.Cu" signal "L5")
		(12 "In5.Cu" signal "L6GND")
		(14 "In6.Cu" signal "L7VCC")
		(16 "In7.Cu" signal "L8VCC")
		(18 "In8.Cu" signal "L9GND")
		(20 "In9.Cu" signal "L10")
		(22 "In10.Cu" signal "L11GND")
		(24 "In11.Cu" signal "L12")
		(26 "In12.Cu" signal "L13GND")
		(2 "B.Cu" signal "BOTTOM")
		(9 "F.Adhes" user "F.Adhesive")
		(11 "B.Adhes" user "B.Adhesive")
		(13 "F.Paste" user "Package Geometry/Pastemask Top")
		(15 "B.Paste" user "Package Geometry/Pastemask Bottom")
		(5 "F.SilkS" user "Ref Des/Silkscreen Top")
		(7 "B.SilkS" user "Ref Des/Silkscreen Bottom")
		(1 "F.Mask" user "Board Geometry/Soldermask Top")
		(3 "B.Mask" user "Board Geometry/Soldermask Bottom")
		(17 "Dwgs.User" user "User.Drawings")
		(19 "Cmts.User" user "User.Comments")
		(21 "Eco1.User" user "User.Eco1")
		(23 "Eco2.User" user "User.Eco2")
		(25 "Edge.Cuts" user "Board Geometry/Outline")
		(27 "Margin" user)
		(31 "F.CrtYd" user "Package Geometry/Place Bound Top")
		(29 "B.CrtYd" user "Package Geometry/Place Bound Bottom")
		(35 "F.Fab" user "Ref Des/Assembly Top")
		(33 "B.Fab" user "Ref Des/Assembly Bottom")
	)
	(footprint ""
		(layer "B.Cu")
		(at 194.700398 -15.222982 90)
		(property "Reference" "J6U1"
			(at 2.530348 39.10711 0)
			(unlocked yes)
			(layer "B.SilkS")
			(effects
				(font
					(size 0.7874 0.5842)
					(thickness 0.1524)
				)
				(justify left mirror)
			)
		)
		(property "Value" ""
			(at 0 0 90)
			(layer "B.Fab")
			(effects
				(font
					(size 1.27 1.27)
				)
				(justify mirror)
			)
		)
		(duplicate_pad_numbers_are_jumpers no)
		(pad "" thru_hole circle
			(at -2.29997 -5.649976 270)
			(size 2.8194 2.8194)
			(drill 2.4384)
			(layers "*.Cu" "*.Mask")
			(remove_unused_layers no)
			(clearance 0.127)
			(thermal_gap 0.127)
		)
		(pad "" thru_hole oval
			(at -2.29997 68.90004 270)
			(size 2.8194 1.5748)
			(drill oval 2.4384 1.1938)
			(layers "*.Cu" "*.Mask")
			(remove_unused_layers no)
			(clearance 0.127)
			(thermal_gap 0.127)
		)
		(pad "" thru_hole circle
			(at -2.29997 132.299964 270)
			(size 2.8194 2.8194)
			(drill 2.4384)
			(layers "*.Cu" "*.Mask")
			(remove_unused_layers no)
			(clearance 0.127)
			(thermal_gap 0.127)
		)
		(pad "1" smd rect
			(at 0 0 270)
			(size 1.8034 0.508)
			(layers "B.Cu" "B.Mask" "B.Paste")
			(net "P12V_NVDIMM_ABC")
		)
		(pad "2" smd rect
			(at 0 0.849884 270)
			(size 1.8034 0.508)
			(layers "B.Cu" "B.Mask" "B.Paste")
			(net "GND")
		)
		(pad "3" smd rect
			(at 0 1.700022 270)
			(size 1.8034 0.508)
			(layers "B.Cu" "B.Mask" "B.Paste")
			(net "M_B_DQ<4>")
		)
		(pad "4" smd rect
			(at 0 2.549906 270)
			(size 1.8034 0.508)
			(layers "B.Cu" "B.Mask" "B.Paste")
			(net "GND")
		)
		(pad "5" smd rect
			(at 0 3.400044 270)
			(size 1.8034 0.508)
			(layers "B.Cu" "B.Mask" "B.Paste")
			(net "M_B_DQ<0>")
		)
		(pad "6" smd rect
			(at 0 4.249928 270)
			(size 1.8034 0.508)
			(layers "B.Cu" "B.Mask" "B.Paste")
			(net "GND")
		)
		(pad "7" smd rect
			(at 0 5.100066 270)
			(size 1.8034 0.508)
			(layers "B.Cu" "B.Mask" "B.Paste")
			(net "M_B_DQS_DP<9>")
		)
		(pad "8" smd rect
			(at 0 5.94995 270)
			(size 1.8034 0.508)
			(layers "B.Cu" "B.Mask" "B.Paste")
			(net "M_B_DQS_DN<9>")
		)
		(pad "9" smd rect
			(at 0 6.800088 270)
			(size 1.8034 0.508)
			(layers "B.Cu" "B.Mask" "B.Paste")
			(net "GND")
		)
		(pad "10" smd rect
			(at 0 7.649972 270)
			(size 1.8034 0.508)
			(layers "B.Cu" "B.Mask" "B.Paste")
			(net "M_B_DQ<6>")
		)
		(pad "11" smd rect
			(at 0 8.50011 270)
			(size 1.8034 0.508)
			(layers "B.Cu" "B.Mask" "B.Paste")
			(net "GND")
		)
		(pad "12" smd rect
			(at 0 9.349994 270)
			(size 1.8034 0.508)
			(layers "B.Cu" "B.Mask" "B.Paste")
			(net "M_B_DQ<2>")
		)
		(pad "13" smd rect
			(at 0 10.199878 270)
			(size 1.8034 0.508)
			(layers "B.Cu" "B.Mask" "B.Paste")
			(net "GND")
		)
		(pad "14" smd rect
			(at 0 11.050016 270)
			(size 1.8034 0.508)
			(layers "B.Cu" "B.Mask" "B.Paste")
			(net "M_B_DQ<12>")
		)
		(pad "15" smd rect
			(at 0 11.8999 270)
			(size 1.8034 0.508)
			(layers "B.Cu" "B.Mask" "B.Paste")
			(net "GND")
		)
		(pad "16" smd rect
			(at 0 12.750038 270)
			(size 1.8034 0.508)
			(layers "B.Cu" "B.Mask" "B.Paste")
			(net "M_B_DQ<8>")
		)
		(pad "17" smd rect
			(at 0 13.599922 270)
			(size 1.8034 0.508)
			(layers "B.Cu" "B.Mask" "B.Paste")
			(net "GND")
		)
		(pad "18" smd rect
			(at 0 14.45006 270)
			(size 1.8034 0.508)
			(layers "B.Cu" "B.Mask" "B.Paste")
			(net "M_B_DQS_DP<10>")
		)
		(pad "19" smd rect
			(at 0 15.299944 270)
			(size 1.8034 0.508)
			(layers "B.Cu" "B.Mask" "B.Paste")
			(net "M_B_DQS_DN<10>")
		)
		(pad "20" smd rect
			(at 0 16.150082 270)
			(size 1.8034 0.508)
			(layers "B.Cu" "B.Mask" "B.Paste")
			(net "GND")
		)
		(pad "21" smd rect
			(at 0 16.999966 270)
			(size 1.8034 0.508)
			(layers "B.Cu" "B.Mask" "B.Paste")
			(net "M_B_DQ<14>")
		)
		(pad "22" smd rect
			(at 0 17.850104 270)
			(size 1.8034 0.508)
			(layers "B.Cu" "B.Mask" "B.Paste")
			(net "GND")
		)
		(pad "23" smd rect
			(at 0 18.699988 270)
			(size 1.8034 0.508)
			(layers "B.Cu" "B.Mask" "B.Paste")
			(net "M_B_DQ<10>")
		)
		(pad "24" smd rect
			(at 0 19.550126 270)
			(size 1.8034 0.508)
			(layers "B.Cu" "B.Mask" "B.Paste")
			(net "GND")
		)
		(pad "25" smd rect
			(at 0 20.40001 270)
			(size 1.8034 0.508)
			(layers "B.Cu" "B.Mask" "B.Paste")
			(net "M_B_DQ<20>")
		)
		(pad "26" smd rect
			(at 0 21.249894 270)
			(size 1.8034 0.508)
			(layers "B.Cu" "B.Mask" "B.Paste")
			(net "GND")
		)
		(pad "27" smd rect
			(at 0 22.100032 270)
			(size 1.8034 0.508)
			(layers "B.Cu" "B.Mask" "B.Paste")
			(net "M_B_DQ<16>")
		)
		(pad "28" smd rect
			(at 0 22.949916 270)
			(size 1.8034 0.508)
			(layers "B.Cu" "B.Mask" "B.Paste")
			(net "GND")
		)
		(pad "29" smd rect
			(at 0 23.800054 270)
			(size 1.8034 0.508)
			(layers "B.Cu" "B.Mask" "B.Paste")
			(net "M_B_DQS_DP<11>")
		)
		(pad "30" smd rect
			(at 0 24.649938 270)
			(size 1.8034 0.508)
			(layers "B.Cu" "B.Mask" "B.Paste")
			(net "M_B_DQS_DN<11>")
		)
		(pad "31" smd rect
			(at 0 25.500076 270)
			(size 1.8034 0.508)
			(layers "B.Cu" "B.Mask" "B.Paste")
			(net "GND")
		)
		(pad "32" smd rect
			(at 0 26.34996 270)
			(size 1.8034 0.508)
			(layers "B.Cu" "B.Mask" "B.Paste")
			(net "M_B_DQ<22>")
		)
		(pad "33" smd rect
			(at 0 27.200098 270)
			(size 1.8034 0.508)
			(layers "B.Cu" "B.Mask" "B.Paste")
			(net "GND")
		)
		(pad "34" smd rect
			(at 0 28.049982 270)
			(size 1.8034 0.508)
			(layers "B.Cu" "B.Mask" "B.Paste")
			(net "M_B_DQ<18>")
		)
		(pad "35" smd rect
			(at 0 28.90012 270)
			(size 1.8034 0.508)
			(layers "B.Cu" "B.Mask" "B.Paste")
			(net "GND")
		)
		(pad "36" smd rect
			(at 0 29.750004 270)
			(size 1.8034 0.508)
			(layers "B.Cu" "B.Mask" "B.Paste")
			(net "M_B_DQ<28>")
		)
		(pad "37" smd rect
			(at 0 30.599888 270)
			(size 1.8034 0.508)
			(layers "B.Cu" "B.Mask" "B.Paste")
			(net "GND")
		)
		(pad "38" smd rect
			(at 0 31.450026 270)
			(size 1.8034 0.508)
			(layers "B.Cu" "B.Mask" "B.Paste")
			(net "M_B_DQ<24>")
		)
		(pad "39" smd rect
			(at 0 32.29991 270)
			(size 1.8034 0.508)
			(layers "B.Cu" "B.Mask" "B.Paste")
			(net "GND")
		)
		(pad "40" smd rect
			(at 0 33.150048 270)
			(size 1.8034 0.508)
			(layers "B.Cu" "B.Mask" "B.Paste")
			(net "M_B_DQS_DP<12>")
		)
		(pad "41" smd rect
			(at 0 33.999932 270)
			(size 1.8034 0.508)
			(layers "B.Cu" "B.Mask" "B.Paste")
			(net "M_B_DQS_DN<12>")
		)
		(pad "42" smd rect
			(at 0 34.85007 270)
			(size 1.8034 0.508)
			(layers "B.Cu" "B.Mask" "B.Paste")
			(net "GND")
		)
		(pad "43" smd rect
			(at 0 35.699954 270)
			(size 1.8034 0.508)
			(layers "B.Cu" "B.Mask" "B.Paste")
			(net "M_B_DQ<30>")
		)
		(pad "44" smd rect
			(at 0 36.550092 270)
			(size 1.8034 0.508)
			(layers "B.Cu" "B.Mask" "B.Paste")
			(net "GND")
		)
		(pad "45" smd rect
			(at 0 37.399976 270)
			(size 1.8034 0.508)
			(layers "B.Cu" "B.Mask" "B.Paste")
			(net "M_B_DQ<26>")
		)
		(pad "46" smd rect
			(at 0 38.250114 270)
			(size 1.8034 0.508)
			(layers "B.Cu" "B.Mask" "B.Paste")
			(net "GND")
		)
		(pad "47" smd rect
			(at 0 39.099998 270)
			(size 1.8034 0.508)
			(layers "B.Cu" "B.Mask" "B.Paste")
			(net "M_B_ECC<4>")
		)
		(pad "48" smd rect
			(at 0 39.949882 270)
			(size 1.8034 0.508)
			(layers "B.Cu" "B.Mask" "B.Paste")
			(net "GND")
		)
		(pad "49" smd rect
			(at 0 40.80002 270)
			(size 1.8034 0.508)
			(layers "B.Cu" "B.Mask" "B.Paste")
			(net "M_B_ECC<0>")
		)
		(pad "50" smd rect
			(at 0 41.649904 270)
			(size 1.8034 0.508)
			(layers "B.Cu" "B.Mask" "B.Paste")
			(net "GND")
		)
		(pad "51" smd rect
			(at 0 42.500042 270)
			(size 1.8034 0.508)
			(layers "B.Cu" "B.Mask" "B.Paste")
			(net "M_B_DQS_DP<17>")
		)
		(pad "52" smd rect
			(at 0 43.349926 270)
			(size 1.8034 0.508)
			(layers "B.Cu" "B.Mask" "B.Paste")
			(net "M_B_DQS_DN<17>")
		)
		(pad "53" smd rect
			(at 0 44.200064 270)
			(size 1.8034 0.508)
			(layers "B.Cu" "B.Mask" "B.Paste")
			(net "GND")
		)
		(pad "54" smd rect
			(at 0 45.049948 270)
			(size 1.8034 0.508)
			(layers "B.Cu" "B.Mask" "B.Paste")
			(net "M_B_ECC<6>")
		)
		(pad "55" smd rect
			(at 0 45.900086 270)
			(size 1.8034 0.508)
			(layers "B.Cu" "B.Mask" "B.Paste")
			(net "GND")
		)
		(pad "56" smd rect
			(at 0 46.74997 270)
			(size 1.8034 0.508)
			(layers "B.Cu" "B.Mask" "B.Paste")
			(net "M_B_ECC<2>")
		)
		(pad "57" smd rect
			(at 0 47.600108 270)
			(size 1.8034 0.508)
			(layers "B.Cu" "B.Mask" "B.Paste")
			(net "GND")
		)
		(pad "58" smd rect
			(at 0 48.449992 270)
			(size 1.8034 0.508)
			(layers "B.Cu" "B.Mask" "B.Paste")
			(net "M_ABC_RST_N")
		)
		(pad "59" smd rect
			(at 0 49.299876 270)
			(size 1.8034 0.508)
			(layers "B.Cu" "B.Mask" "B.Paste")
			(net "PVDDQ_ABC")
		)
		(pad "60" smd rect
			(at 0 50.150014 270)
			(size 1.8034 0.508)
			(layers "B.Cu" "B.Mask" "B.Paste")
			(net "M_B_CKE<2>")
		)
		(pad "61" smd rect
			(at 0 50.999898 270)
			(size 1.8034 0.508)
			(layers "B.Cu" "B.Mask" "B.Paste")
			(net "PVDDQ_ABC")
		)
		(pad "62" smd rect
			(at 0 51.850036 270)
			(size 1.8034 0.508)
			(layers "B.Cu" "B.Mask" "B.Paste")
			(net "M_B_ACT_N")
		)
		(pad "63" smd rect
			(at 0 52.69992 270)
			(size 1.8034 0.508)
			(layers "B.Cu" "B.Mask" "B.Paste")
			(net "M_B_BG<0>")
		)
		(pad "64" smd rect
			(at 0 53.550058 270)
			(size 1.8034 0.508)
			(layers "B.Cu" "B.Mask" "B.Paste")
			(net "PVDDQ_ABC")
		)
		(pad "65" smd rect
			(at 0 54.399942 270)
			(size 1.8034 0.508)
			(layers "B.Cu" "B.Mask" "B.Paste")
			(net "M_B_MA<12>")
		)
		(pad "66" smd rect
			(at 0 55.25008 270)
			(size 1.8034 0.508)
			(layers "B.Cu" "B.Mask" "B.Paste")
			(net "M_B_MA<9>")
		)
		(pad "67" smd rect
			(at 0 56.099964 270)
			(size 1.8034 0.508)
			(layers "B.Cu" "B.Mask" "B.Paste")
			(net "PVDDQ_ABC")
		)
		(pad "68" smd rect
			(at 0 56.950102 270)
			(size 1.8034 0.508)
			(layers "B.Cu" "B.Mask" "B.Paste")
			(net "M_B_MA<8>")
		)
		(pad "69" smd rect
			(at 0 57.799986 270)
			(size 1.8034 0.508)
			(layers "B.Cu" "B.Mask" "B.Paste")
			(net "M_B_MA<6>")
		)
		(pad "70" smd rect
			(at 0 58.650124 270)
			(size 1.8034 0.508)
			(layers "B.Cu" "B.Mask" "B.Paste")
			(net "PVDDQ_ABC")
		)
		(pad "71" smd rect
			(at 0 59.500008 270)
			(size 1.8034 0.508)
			(layers "B.Cu" "B.Mask" "B.Paste")
			(net "M_B_MA<3>")
		)
		(pad "72" smd rect
			(at 0 60.349892 270)
			(size 1.8034 0.508)
			(layers "B.Cu" "B.Mask" "B.Paste")
			(net "M_B_MA<1>")
		)
		(pad "73" smd rect
			(at 0 61.20003 270)
			(size 1.8034 0.508)
			(layers "B.Cu" "B.Mask" "B.Paste")
			(net "PVDDQ_ABC")
		)
		(pad "74" smd rect
			(at 0 62.049914 270)
			(size 1.8034 0.508)
			(layers "B.Cu" "B.Mask" "B.Paste")
			(net "M_B_CLK_DP<2>")
		)
		(pad "75" smd rect
			(at 0 62.900052 270)
			(size 1.8034 0.508)
			(layers "B.Cu" "B.Mask" "B.Paste")
			(net "M_B_CLK_DN<2>")
		)
		(pad "76" smd rect
			(at 0 63.749936 270)
			(size 1.8034 0.508)
			(layers "B.Cu" "B.Mask" "B.Paste")
			(net "PVDDQ_ABC")
		)
		(pad "77" smd rect
			(at 0 64.600074 270)
			(size 1.8034 0.508)
			(layers "B.Cu" "B.Mask" "B.Paste")
			(net "PVTT_ABC")
		)
		(pad "78" smd rect
			(at 0 70.550024 270)
			(size 1.8034 0.508)
			(layers "B.Cu" "B.Mask" "B.Paste")
			(net "FM_DIMM_EVENT_COD_N")
		)
		(pad "79" smd rect
			(at 0 71.399908 270)
			(size 1.8034 0.508)
			(layers "B.Cu" "B.Mask" "B.Paste")
			(net "M_B_MA<0>")
		)
		(pad "80" smd rect
			(at 0 72.250046 270)
			(size 1.8034 0.508)
			(layers "B.Cu" "B.Mask" "B.Paste")
			(net "PVDDQ_ABC")
		)
		(pad "81" smd rect
			(at 0 73.09993 270)
			(size 1.8034 0.508)
			(layers "B.Cu" "B.Mask" "B.Paste")
			(net "M_B_BA<0>")
		)
		(pad "82" smd rect
			(at 0 73.950068 270)
			(size 1.8034 0.508)
			(layers "B.Cu" "B.Mask" "B.Paste")
			(net "M_B_MA<16>")
		)
		(pad "83" smd rect
			(at 0 74.799952 270)
			(size 1.8034 0.508)
			(layers "B.Cu" "B.Mask" "B.Paste")
			(net "PVDDQ_ABC")
		)
		(pad "84" smd rect
			(at 0 75.65009 270)
			(size 1.8034 0.508)
			(layers "B.Cu" "B.Mask" "B.Paste")
			(net "M_B_CS_N<4>")
		)
		(pad "85" smd rect
			(at 0 76.499974 270)
			(size 1.8034 0.508)
			(layers "B.Cu" "B.Mask" "B.Paste")
			(net "PVDDQ_ABC")
		)
		(pad "86" smd rect
			(at 0 77.350112 270)
			(size 1.8034 0.508)
			(layers "B.Cu" "B.Mask" "B.Paste")
			(net "M_B_MA<15>")
		)
		(pad "87" smd rect
			(at 0 78.199996 270)
			(size 1.8034 0.508)
			(layers "B.Cu" "B.Mask" "B.Paste")
			(net "M_B_ODT<2>")
		)
		(pad "88" smd rect
			(at 0 79.04988 270)
			(size 1.8034 0.508)
			(layers "B.Cu" "B.Mask" "B.Paste")
			(net "PVDDQ_ABC")
		)
		(pad "89" smd rect
			(at 0 79.900018 270)
			(size 1.8034 0.508)
			(layers "B.Cu" "B.Mask" "B.Paste")
			(net "M_B_CS_N<5>")
		)
		(pad "90" smd rect
			(at 0 80.749902 270)
			(size 1.8034 0.508)
			(layers "B.Cu" "B.Mask" "B.Paste")
			(net "PVDDQ_ABC")
		)
		(pad "91" smd rect
			(at 0 81.60004 270)
			(size 1.8034 0.508)
			(layers "B.Cu" "B.Mask" "B.Paste")
			(net "M_B_ODT<3>")
		)
		(pad "92" smd rect
			(at 0 82.449924 270)
			(size 1.8034 0.508)
			(layers "B.Cu" "B.Mask" "B.Paste")
			(net "PVDDQ_ABC")
		)
		(pad "93" smd rect
			(at 0 83.300062 270)
			(size 1.8034 0.508)
			(layers "B.Cu" "B.Mask" "B.Paste")
			(net "M_B_CS_N<6>")
		)
		(pad "94" smd rect
			(at 0 84.149946 270)
			(size 1.8034 0.508)
			(layers "B.Cu" "B.Mask" "B.Paste")
			(net "GND")
		)
		(pad "95" smd rect
			(at 0 85.000084 270)
			(size 1.8034 0.508)
			(layers "B.Cu" "B.Mask" "B.Paste")
			(net "M_B_DQ<36>")
		)
		(pad "96" smd rect
			(at 0 85.849968 270)
			(size 1.8034 0.508)
			(layers "B.Cu" "B.Mask" "B.Paste")
			(net "GND")
		)
		(pad "97" smd rect
			(at 0 86.700106 270)
			(size 1.8034 0.508)
			(layers "B.Cu" "B.Mask" "B.Paste")
			(net "M_B_DQ<32>")
		)
		(pad "98" smd rect
			(at 0 87.54999 270)
			(size 1.8034 0.508)
			(layers "B.Cu" "B.Mask" "B.Paste")
			(net "GND")
		)
		(pad "99" smd rect
			(at 0 88.399874 270)
			(size 1.8034 0.508)
			(layers "B.Cu" "B.Mask" "B.Paste")
			(net "M_B_DQS_DP<13>")
		)
		(pad "100" smd rect
			(at 0 89.250012 270)
			(size 1.8034 0.508)
			(layers "B.Cu" "B.Mask" "B.Paste")
			(net "M_B_DQS_DN<13>")
		)
		(pad "101" smd rect
			(at 0 90.099896 270)
			(size 1.8034 0.508)
			(layers "B.Cu" "B.Mask" "B.Paste")
			(net "GND")
		)
		(pad "102" smd rect
			(at 0 90.950034 270)
			(size 1.8034 0.508)
			(layers "B.Cu" "B.Mask" "B.Paste")
			(net "M_B_DQ<38>")
		)
		(pad "103" smd rect
			(at 0 91.799918 270)
			(size 1.8034 0.508)
			(layers "B.Cu" "B.Mask" "B.Paste")
			(net "GND")
		)
		(pad "104" smd rect
			(at 0 92.650056 270)
			(size 1.8034 0.508)
			(layers "B.Cu" "B.Mask" "B.Paste")
			(net "M_B_DQ<34>")
		)
		(pad "105" smd rect
			(at 0 93.49994 270)
			(size 1.8034 0.508)
			(layers "B.Cu" "B.Mask" "B.Paste")
			(net "GND")
		)
		(pad "106" smd rect
			(at 0 94.350078 270)
			(size 1.8034 0.508)
			(layers "B.Cu" "B.Mask" "B.Paste")
			(net "M_B_DQ<44>")
		)
		(pad "107" smd rect
			(at 0 95.199962 270)
			(size 1.8034 0.508)
			(layers "B.Cu" "B.Mask" "B.Paste")
			(net "GND")
		)
		(pad "108" smd rect
			(at 0 96.0501 270)
			(size 1.8034 0.508)
			(layers "B.Cu" "B.Mask" "B.Paste")
			(net "M_B_DQ<40>")
		)
		(pad "109" smd rect
			(at 0 96.899984 270)
			(size 1.8034 0.508)
			(layers "B.Cu" "B.Mask" "B.Paste")
			(net "GND")
		)
		(pad "110" smd rect
			(at 0 97.750122 270)
			(size 1.8034 0.508)
			(layers "B.Cu" "B.Mask" "B.Paste")
			(net "M_B_DQS_DP<14>")
		)
		(pad "111" smd rect
			(at 0 98.600006 270)
			(size 1.8034 0.508)
			(layers "B.Cu" "B.Mask" "B.Paste")
			(net "M_B_DQS_DN<14>")
		)
		(pad "112" smd rect
			(at 0 99.44989 270)
			(size 1.8034 0.508)
			(layers "B.Cu" "B.Mask" "B.Paste")
			(net "GND")
		)
		(pad "113" smd rect
			(at 0 100.300028 270)
			(size 1.8034 0.508)
			(layers "B.Cu" "B.Mask" "B.Paste")
			(net "M_B_DQ<46>")
		)
		(pad "114" smd rect
			(at 0 101.149912 270)
			(size 1.8034 0.508)
			(layers "B.Cu" "B.Mask" "B.Paste")
			(net "GND")
		)
		(pad "115" smd rect
			(at 0 102.00005 270)
			(size 1.8034 0.508)
			(layers "B.Cu" "B.Mask" "B.Paste")
			(net "M_B_DQ<42>")
		)
		(pad "116" smd rect
			(at 0 102.849934 270)
			(size 1.8034 0.508)
			(layers "B.Cu" "B.Mask" "B.Paste")
			(net "GND")
		)
		(pad "117" smd rect
			(at 0 103.700072 270)
			(size 1.8034 0.508)
			(layers "B.Cu" "B.Mask" "B.Paste")
			(net "M_B_DQ<52>")
		)
		(pad "118" smd rect
			(at 0 104.549956 270)
			(size 1.8034 0.508)
			(layers "B.Cu" "B.Mask" "B.Paste")
			(net "GND")
		)
		(pad "119" smd rect
			(at 0 105.400094 270)
			(size 1.8034 0.508)
			(layers "B.Cu" "B.Mask" "B.Paste")
			(net "M_B_DQ<48>")
		)
		(pad "120" smd rect
			(at 0 106.249978 270)
			(size 1.8034 0.508)
			(layers "B.Cu" "B.Mask" "B.Paste")
			(net "GND")
		)
	)
)
